# T6G (Grand Teton) — schematic netlist excerpt (pin names and nets, part order shuffled) for the footprints in the layout excerpt that follows; sources: Cadence DE-HDL packaged netlist, KiCad conversion of 04192023_DAF0TMB3IC0_F0TG_MB_C_brd_V02_OCP.brd

PR394  Q_RES  0 5% EMPTY  pkg 0402LF  page 225 : A = PVDD11_S3_P1_PVCC ; B = P3V3_AUX
R6782  Q_RES  33 5% CHIP  pkg 0402LF  page 151 : A = SMB_MUX_RT_ROM_R1_SCL ; B = SMB_HOST_CLK_3V3AUX_SCL_R1
R6159  Q_RES  0 5% CHIP  pkg 0201LF  page 113 : A = P2E_MB_BMC_RX_DN<0> ; B = P2E_MB_BMC_RX_R2_DN<0>

(kicad_pcb
	(version 20260206)
	(generator "pcbnew")
	(generator_version "10.0")
	(general
		(thickness 1.6)
		(legacy_teardrops no)
	)
	(paper "A4")
	(title_block
		(title "04192023_DAF0TMB3IC0_F0TG_MB_C_brd_V02_OCP.brd")
		(comment 1 "Grand Teton / footprints 135-137 of 8354")
	)
	(layers
		(0 "F.Cu" signal "TOP")
		(4 "In1.Cu" signal "GND")
		(6 "In2.Cu" signal "IN1")
		(8 "In3.Cu" signal "GND1")
		(10 "In4.Cu" signal "IN2")
		(12 "In5.Cu" signal "GND2")
		(14 "In6.Cu" signal "IN3")
		(16 "In7.Cu" signal "GND3")
		(18 "In8.Cu" signal "VCC")
		(20 "In9.Cu" signal "VCC1")
		(22 "In10.Cu" signal "GND4")
		(24 "In11.Cu" signal "IN4")
		(26 "In12.Cu" signal "GND5")
		(28 "In13.Cu" signal "IN5")
		(30 "In14.Cu" signal "GND6")
		(32 "In15.Cu" signal "IN6")
		(34 "In16.Cu" signal "GND7")
		(2 "B.Cu" signal "BOTTOM")
		(9 "F.Adhes" user "F.Adhesive")
		(11 "B.Adhes" user "B.Adhesive")
		(13 "F.Paste" user "Package Geometry/Pastemask Top")
		(15 "B.Paste" user "Package Geometry/Pastemask Bottom")
		(5 "F.SilkS" user "Ref Des/Silkscreen Top")
		(7 "B.SilkS" user "Ref Des/Silkscreen Bottom")
		(1 "F.Mask" user "Board Geometry/Soldermask Top")
		(3 "B.Mask" user "Board Geometry/Soldermask Bottom")
		(17 "Dwgs.User" user "User.Drawings")
		(19 "Cmts.User" user "User.Comments")
		(21 "Eco1.User" user "User.Eco1")
		(23 "Eco2.User" user "User.Eco2")
		(25 "Edge.Cuts" user "Board Geometry/Outline")
		(27 "Margin" user)
		(31 "F.CrtYd" user "Package Geometry/Place Bound Top")
		(29 "B.CrtYd" user "Package Geometry/Place Bound Bottom")
		(35 "F.Fab" user "Ref Des/Assembly Top")
		(33 "B.Fab" user "Ref Des/Assembly Bottom")
	)
	(footprint ""
		(layer "F.Cu")
		(at 178.221894 -353.966272 90)
		(property "Reference" "PR394"
			(at 0 0 90)
			(layer "F.SilkS")
			(hide yes)
			(effects
				(font
					(size 1.27 1.27)
				)
			)
		)
		(property "Value" ""
			(at 0 0 90)
			(layer "F.Fab")
			(effects
				(font
					(size 1.27 1.27)
				)
			)
		)
		(duplicate_pad_numbers_are_jumpers no)
		(fp_line
			(start 0.7874 -0.4064)
			(end 0.7874 0.4064)
			(stroke
				(width 0.1524)
				(type default)
			)
			(layer "F.SilkS")
		)
		(fp_line
			(start -0.7874 -0.4064)
			(end 0.7874 -0.4064)
			(stroke
				(width 0.1524)
				(type default)
			)
			(layer "F.SilkS")
		)
		(fp_line
			(start 0.7874 0.4064)
			(end -0.7874 0.4064)
			(stroke
				(width 0.1524)
				(type default)
			)
			(layer "F.SilkS")
		)
		(fp_line
			(start -0.7874 0.4064)
			(end -0.7874 -0.4064)
			(stroke
				(width 0.1524)
				(type default)
			)
			(layer "F.SilkS")
		)
		(fp_line
			(start -0.12065 -0.305054)
			(end -0.12065 -0.2794)
			(stroke
				(width 0.1)
				(type default)
			)
			(layer "F.Fab")
		)
		(fp_line
			(start -0.67945 -0.305054)
			(end -0.12065 -0.305054)
			(stroke
				(width 0.1)
				(type default)
			)
			(layer "F.Fab")
		)
		(fp_line
			(start 0.67945 -0.3048)
			(end 0.67945 0.3048)
			(stroke
				(width 0.1)
				(type default)
			)
			(layer "F.Fab")
		)
		(fp_line
			(start 0.12065 -0.3048)
			(end 0.67945 -0.3048)
			(stroke
				(width 0.1)
				(type default)
			)
			(layer "F.Fab")
		)
		(fp_line
			(start 0.12065 -0.2794)
			(end 0.12065 -0.3048)
			(stroke
				(width 0.1)
				(type default)
			)
			(layer "F.Fab")
		)
		(fp_line
			(start -0.12065 -0.2794)
			(end 0.12065 -0.2794)
			(stroke
				(width 0.1)
				(type default)
			)
			(layer "F.Fab")
		)
		(fp_line
			(start 0.120396 0.2794)
			(end -0.12065 0.2794)
			(stroke
				(width 0.1)
				(type default)
			)
			(layer "F.Fab")
		)
		(fp_line
			(start -0.12065 0.2794)
			(end -0.12065 0.3048)
			(stroke
				(width 0.1)
				(type default)
			)
			(layer "F.Fab")
		)
		(fp_line
			(start 0.67945 0.3048)
			(end 0.120396 0.3048)
			(stroke
				(width 0.1)
				(type default)
			)
			(layer "F.Fab")
		)
		(fp_line
			(start 0.120396 0.3048)
			(end 0.120396 0.2794)
			(stroke
				(width 0.1)
				(type default)
			)
			(layer "F.Fab")
		)
		(fp_line
			(start -0.12065 0.3048)
			(end -0.67945 0.3048)
			(stroke
				(width 0.1)
				(type default)
			)
			(layer "F.Fab")
		)
		(fp_line
			(start -0.67945 0.3048)
			(end -0.67945 -0.305054)
			(stroke
				(width 0.1)
				(type default)
			)
			(layer "F.Fab")
		)
		(pad "1" smd circle
			(at -0.40005 0 90)
			(size 0 0)
			(layers "F.Cu" "F.Mask" "F.Paste")
			(net "PVDD11_S3_P1_PVCC")
		)
		(pad "2" smd circle
			(at 0.40005 0 90)
			(size 0 0)
			(layers "F.Cu" "F.Mask" "F.Paste")
			(net "P3V3_AUX")
		)
	)
	(footprint ""
		(layer "F.Cu")
		(at 27.487626 -427.612302 180)
		(property "Reference" "R6159"
			(at 0 0 180)
			(layer "F.SilkS")
			(hide yes)
			(effects
				(font
					(size 1.27 1.27)
				)
			)
		)
		(property "Value" ""
			(at 0 0 180)
			(layer "F.Fab")
			(effects
				(font
					(size 1.27 1.27)
				)
			)
		)
		(duplicate_pad_numbers_are_jumpers no)
		(fp_line
			(start 0.32512 0.175006)
			(end -0.32512 0.175006)
			(stroke
				(width 0.1)
				(type default)
			)
			(layer "F.Fab")
		)
		(fp_line
			(start 0.32512 -0.175006)
			(end 0.32512 0.175006)
			(stroke
				(width 0.1)
				(type default)
			)
			(layer "F.Fab")
		)
		(fp_line
			(start -0.32512 0.175006)
			(end -0.32512 -0.175006)
			(stroke
				(width 0.1)
				(type default)
			)
			(layer "F.Fab")
		)
		(fp_line
			(start -0.32512 -0.175006)
			(end 0.32512 -0.175006)
			(stroke
				(width 0.1)
				(type default)
			)
			(layer "F.Fab")
		)
		(pad "1" smd rect
			(at -0.2667 0 180)
			(size 0.3048 0.381)
			(layers "F.Cu" "F.Mask" "F.Paste")
			(net "P2E_MB_BMC_RX_DN<0>")
		)
		(pad "2" smd rect
			(at 0.2667 0)
			(size 0.3048 0.381)
			(layers "F.Cu" "F.Mask" "F.Paste")
			(net "P2E_MB_BMC_RX_R2_DN<0>")
		)
	)
	(footprint ""
		(layer "F.Cu")
		(at 277.591774 -414.00603)
		(property "Reference" "R6782"
			(at 0 0 0)
			(layer "F.SilkS")
			(hide yes)
			(effects
				(font
					(size 1.27 1.27)
				)
			)
		)
		(property "Value" ""
			(at 0 0 0)
			(layer "F.Fab")
			(effects
				(font
					(size 1.27 1.27)
				)
			)
		)
		(duplicate_pad_numbers_are_jumpers no)
		(fp_line
			(start -0.7874 -0.4064)
			(end 0.7874 -0.4064)
			(stroke
				(width 0.1524)
				(type default)
			)
			(layer "F.SilkS")
		)
		(fp_line
			(start -0.7874 0.4064)
			(end -0.7874 -0.4064)
			(stroke
				(width 0.1524)
				(type default)
			)
			(layer "F.SilkS")
		)
		(fp_line
			(start 0.7874 -0.4064)
			(end 0.7874 0.4064)
			(stroke
				(width 0.1524)
				(type default)
			)
			(layer "F.SilkS")
		)
		(fp_line
			(start 0.7874 0.4064)
			(end -0.7874 0.4064)
			(stroke
				(width 0.1524)
				(type default)
			)
			(layer "F.SilkS")
		)
		(fp_line
			(start -0.67945 -0.305054)
			(end -0.12065 -0.305054)
			(stroke
				(width 0.1)
				(type default)
			)
			(layer "F.Fab")
		)
		(fp_line
			(start -0.67945 0.3048)
			(end -0.67945 -0.305054)
			(stroke
				(width 0.1)
				(type default)
			)
			(layer "F.Fab")
		)
		(fp_line
			(start -0.12065 -0.305054)
			(end -0.12065 -0.2794)
			(stroke
				(width 0.1)
				(type default)
			)
			(layer "F.Fab")
		)
		(fp_line
			(start -0.12065 -0.2794)
			(end 0.12065 -0.2794)
			(stroke
				(width 0.1)
				(type default)
			)
			(layer "F.Fab")
		)
		(fp_line
			(start -0.12065 0.2794)
			(end -0.12065 0.3048)
			(stroke
				(width 0.1)
				(type default)
			)
			(layer "F.Fab")
		)
		(fp_line
			(start -0.12065 0.3048)
			(end -0.67945 0.3048)
			(stroke
				(width 0.1)
				(type default)
			)
			(layer "F.Fab")
		)
		(fp_line
			(start 0.120396 0.2794)
			(end -0.12065 0.2794)
			(stroke
				(width 0.1)
				(type default)
			)
			(layer "F.Fab")
		)
		(fp_line
			(start 0.120396 0.3048)
			(end 0.120396 0.2794)
			(stroke
				(width 0.1)
				(type default)
			)
			(layer "F.Fab")
		)
		(fp_line
			(start 0.12065 -0.3048)
			(end 0.67945 -0.3048)
			(stroke
				(width 0.1)
				(type default)
			)
			(layer "F.Fab")
		)
		(fp_line
			(start 0.12065 -0.2794)
			(end 0.12065 -0.3048)
			(stroke
				(width 0.1)
				(type default)
			)
			(layer "F.Fab")
		)
		(fp_line
			(start 0.67945 -0.3048)
			(end 0.67945 0.3048)
			(stroke
				(width 0.1)
				(type default)
			)
			(layer "F.Fab")
		)
		(fp_line
			(start 0.67945 0.3048)
			(end 0.120396 0.3048)
			(stroke
				(width 0.1)
				(type default)
			)
			(layer "F.Fab")
		)
		(pad "1" smd circle
			(at -0.40005 0)
			(size 0 0)
			(layers "F.Cu" "F.Mask" "F.Paste")
			(net "SMB_MUX_RT_ROM_R1_SCL")
		)
		(pad "2" smd circle
			(at 0.40005 0)
			(size 0 0)
			(layers "F.Cu" "F.Mask" "F.Paste")
			(net "SMB_HOST_CLK_3V3AUX_SCL_R1")
		)
	)
)
